(kicad_pcb
	(version 20260206)
	(generator "pcbnew")
	(generator_version "10.0")
	(general
		(thickness 1.6)
		(legacy_teardrops no)
	)
	(paper "A4")
	(title_block
		(title "03242023_DA0F0TMBIJ0_F0T_Motherboard_J_brd_V01_OCP.brd")
		(comment 1 "Grand Teton / footprint 3039 of 6105 (U2), pads 211-318 of 4677")
	)
	(layers
		(0 "F.Cu" signal "TOP")
		(4 "In1.Cu" signal "GND")
		(6 "In2.Cu" signal "IN1")
		(8 "In3.Cu" signal "GND1")
		(10 "In4.Cu" signal "IN2")
		(12 "In5.Cu" signal "GND2")
		(14 "In6.Cu" signal "IN3")
		(16 "In7.Cu" signal "GND3")
		(18 "In8.Cu" signal "VCC")
		(20 "In9.Cu" signal "VCC1")
		(22 "In10.Cu" signal "GND4")
		(24 "In11.Cu" signal "IN4")
		(26 "In12.Cu" signal "GND5")
		(28 "In13.Cu" signal "IN5")
		(30 "In14.Cu" signal "GND6")
		(32 "In15.Cu" signal "IN6")
		(34 "In16.Cu" signal "GND7")
		(2 "B.Cu" signal "BOTTOM")
		(9 "F.Adhes" user "F.Adhesive")
		(11 "B.Adhes" user "B.Adhesive")
		(13 "F.Paste" user "Package Geometry/Pastemask Top")
		(15 "B.Paste" user "Package Geometry/Pastemask Bottom")
		(5 "F.SilkS" user "Ref Des/Silkscreen Top")
		(7 "B.SilkS" user "Ref Des/Silkscreen Bottom")
		(1 "F.Mask" user "Board Geometry/Soldermask Top")
		(3 "B.Mask" user "Board Geometry/Soldermask Bottom")
		(17 "Dwgs.User" user "User.Drawings")
		(19 "Cmts.User" user "User.Comments")
		(21 "Eco1.User" user "User.Eco1")
		(23 "Eco2.User" user "User.Eco2")
		(25 "Edge.Cuts" user "Board Geometry/Outline")
		(27 "Margin" user)
		(31 "F.CrtYd" user "Package Geometry/Place Bound Top")
		(29 "B.CrtYd" user "Package Geometry/Place Bound Bottom")
		(35 "F.Fab" user "Ref Des/Assembly Top")
		(33 "B.Fab" user "Ref Des/Assembly Bottom")
	)
	(footprint ""
		(layer "F.Cu")
		(at 359.870248 -251.76988 90)
		(property "Reference" "U2"
			(at -74.416158 -44.488608 0)
			(unlocked yes)
			(layer "F.SilkS")
			(effects
				(font
					(size 1.6002 1.1938)
					(thickness 0.1524)
				)
				(justify left)
			)
		)
		(property "Value" ""
			(at 0 0 90)
			(layer "F.Fab")
			(effects
				(font
					(size 1.27 1.27)
				)
			)
		)
		(duplicate_pad_numbers_are_jumpers no)
		(pad "AE9" smd circle
			(at -30.914086 -15.796514 270)
			(size 0.4318 0.4318)
			(layers "F.Cu" "F.Mask" "F.Paste")
			(net "P5E_CPU0_PE0_RX_DN<7>")
		)
		(pad "AE11" smd circle
			(at -29.2862 -15.796514 270)
			(size 0.4318 0.4318)
			(layers "F.Cu" "F.Mask" "F.Paste")
			(net "PVCCFA_EHV_FIVRA_CPU0")
		)
		(pad "AE13" smd circle
			(at -27.658314 -15.796514 270)
			(size 0.4318 0.4318)
			(layers "F.Cu" "F.Mask" "F.Paste")
			(net "P5E_CPU0_PE0_TX_DN<6>")
		)
		(pad "AE15" smd circle
			(at -26.030682 -15.796514 270)
			(size 0.4318 0.4318)
			(layers "F.Cu" "F.Mask" "F.Paste")
			(net "PVCCFA_EHV_FIVRA_CPU0")
		)
		(pad "AE17" smd circle
			(at -24.402796 -15.796514 270)
			(size 0.4318 0.4318)
			(layers "F.Cu" "F.Mask" "F.Paste")
			(net "GND")
		)
		(pad "AE19" smd circle
			(at -22.77491 -15.796514 270)
			(size 0.4318 0.4318)
			(layers "F.Cu" "F.Mask" "F.Paste")
			(net "GND")
		)
		(pad "AE21" smd circle
			(at -21.147278 -15.796514 270)
			(size 0.4318 0.4318)
			(layers "F.Cu" "F.Mask" "F.Paste")
			(net "GND")
		)
		(pad "AE23" smd circle
			(at -19.519392 -15.796514 270)
			(size 0.4318 0.4318)
			(layers "F.Cu" "F.Mask" "F.Paste")
			(net "GND")
		)
		(pad "AE25" smd circle
			(at -17.89176 -15.796514 270)
			(size 0.4318 0.4318)
			(layers "F.Cu" "F.Mask" "F.Paste")
			(net "GND")
		)
		(pad "AE27" smd circle
			(at -16.263874 -15.796514 270)
			(size 0.4318 0.4318)
			(layers "F.Cu" "F.Mask" "F.Paste")
			(net "GND")
		)
		(pad "AE29" smd circle
			(at -14.635988 -15.796514 270)
			(size 0.4318 0.4318)
			(layers "F.Cu" "F.Mask" "F.Paste")
			(net "GND")
		)
		(pad "AE31" smd circle
			(at -13.008356 -15.796514 270)
			(size 0.4318 0.4318)
			(layers "F.Cu" "F.Mask" "F.Paste")
			(net "GND")
		)
		(pad "AE33" smd circle
			(at -11.380724 -15.796514 270)
			(size 0.4318 0.4318)
			(layers "F.Cu" "F.Mask" "F.Paste")
			(net "GND")
		)
		(pad "AE35" smd circle
			(at -9.752838 -15.796514 270)
			(size 0.4318 0.4318)
			(layers "F.Cu" "F.Mask" "F.Paste")
			(net "GND")
		)
		(pad "AE37" smd circle
			(at -8.124952 -15.796514 270)
			(size 0.4318 0.4318)
			(layers "F.Cu" "F.Mask" "F.Paste")
			(net "GND")
		)
		(pad "AE39" smd circle
			(at -6.49732 -15.796514 270)
			(size 0.4318 0.4318)
			(layers "F.Cu" "F.Mask" "F.Paste")
			(net "GND")
		)
		(pad "AE41" smd circle
			(at -4.869434 -15.796514 270)
			(size 0.4318 0.4318)
			(layers "F.Cu" "F.Mask" "F.Paste")
			(net "GND")
		)
		(pad "AE43" smd circle
			(at -3.241802 -15.796514 270)
			(size 0.4318 0.4318)
			(layers "F.Cu" "F.Mask" "F.Paste")
			(net "GND")
		)
		(pad "AE45" smd circle
			(at -1.613916 -15.796514 270)
			(size 0.4318 0.4318)
			(layers "F.Cu" "F.Mask" "F.Paste")
			(net "GND")
		)
		(pad "AE48" smd circle
			(at 2.427732 -15.686532 270)
			(size 0.4318 0.4318)
			(layers "F.Cu" "F.Mask" "F.Paste")
			(net "GND")
		)
		(pad "AE50" smd circle
			(at 4.055618 -15.686532 270)
			(size 0.4318 0.4318)
			(layers "F.Cu" "F.Mask" "F.Paste")
			(net "GND")
		)
		(pad "AE52" smd circle
			(at 5.68325 -15.686532 270)
			(size 0.4318 0.4318)
			(layers "F.Cu" "F.Mask" "F.Paste")
			(net "GND")
		)
		(pad "AE54" smd circle
			(at 7.311136 -15.686532 270)
			(size 0.4318 0.4318)
			(layers "F.Cu" "F.Mask" "F.Paste")
			(net "GND")
		)
		(pad "AE56" smd circle
			(at 8.939022 -15.686532 270)
			(size 0.4318 0.4318)
			(layers "F.Cu" "F.Mask" "F.Paste")
			(net "GND")
		)
		(pad "AE58" smd circle
			(at 10.566654 -15.686532 270)
			(size 0.4318 0.4318)
			(layers "F.Cu" "F.Mask" "F.Paste")
			(net "GND")
		)
		(pad "AE60" smd circle
			(at 12.19454 -15.686532 270)
			(size 0.4318 0.4318)
			(layers "F.Cu" "F.Mask" "F.Paste")
			(net "GND")
		)
		(pad "AE62" smd circle
			(at 13.822426 -15.686532 270)
			(size 0.4318 0.4318)
			(layers "F.Cu" "F.Mask" "F.Paste")
			(net "GND")
		)
		(pad "AE64" smd circle
			(at 15.450058 -15.686532 270)
			(size 0.4318 0.4318)
			(layers "F.Cu" "F.Mask" "F.Paste")
			(net "GND")
		)
		(pad "AE66" smd circle
			(at 17.07769 -15.686532 270)
			(size 0.4318 0.4318)
			(layers "F.Cu" "F.Mask" "F.Paste")
			(net "GND")
		)
		(pad "AE68" smd circle
			(at 18.705576 -15.686532 270)
			(size 0.4318 0.4318)
			(layers "F.Cu" "F.Mask" "F.Paste")
			(net "GND")
		)
		(pad "AE70" smd circle
			(at 20.333462 -15.686532 270)
			(size 0.4318 0.4318)
			(layers "F.Cu" "F.Mask" "F.Paste")
			(net "GND")
		)
		(pad "AE72" smd circle
			(at 21.961094 -15.686532 270)
			(size 0.4318 0.4318)
			(layers "F.Cu" "F.Mask" "F.Paste")
			(net "GND")
		)
		(pad "AE74" smd circle
			(at 23.58898 -15.686532 270)
			(size 0.4318 0.4318)
			(layers "F.Cu" "F.Mask" "F.Paste")
			(net "GND")
		)
		(pad "AE76" smd circle
			(at 25.216612 -15.686532 270)
			(size 0.4318 0.4318)
			(layers "F.Cu" "F.Mask" "F.Paste")
			(net "GND")
		)
		(pad "AE78" smd circle
			(at 26.844498 -15.686532 270)
			(size 0.4318 0.4318)
			(layers "F.Cu" "F.Mask" "F.Paste")
			(net "GND")
		)
		(pad "AE80" smd circle
			(at 28.472384 -15.686532 270)
			(size 0.4318 0.4318)
			(layers "F.Cu" "F.Mask" "F.Paste")
			(net "UPI_CPU1_CPU0_P2P2_DP<17>")
		)
		(pad "AE82" smd circle
			(at 30.100016 -15.686532 270)
			(size 0.4318 0.4318)
			(layers "F.Cu" "F.Mask" "F.Paste")
			(net "UPI_CPU1_CPU0_P2P2_DP<14>")
		)
		(pad "AE84" smd circle
			(at 31.727902 -15.686532 270)
			(size 0.4318 0.4318)
			(layers "F.Cu" "F.Mask" "F.Paste")
			(net "GND")
		)
		(pad "AE86" smd circle
			(at 33.355534 -15.686532 270)
			(size 0.4318 0.4318)
			(layers "F.Cu" "F.Mask" "F.Paste")
			(net "P5E_CPU0_PE4_TX_DN<7>")
		)
		(pad "AE88" smd circle
			(at 34.98342 -15.686532 270)
			(size 0.4318 0.4318)
			(layers "F.Cu" "F.Mask" "F.Paste")
			(net "GND")
		)
		(pad "AE90" smd circle
			(at 36.611306 -15.686532 270)
			(size 0.4318 0.4318)
			(layers "F.Cu" "F.Mask" "F.Paste")
			(net "P5E_CPU0_PE4_RX_DP<7>")
		)
		(pad "AF2" smd circle
			(at -36.611306 -15.326868 270)
			(size 0.4318 0.4318)
			(layers "F.Cu" "F.Mask" "F.Paste")
			(net "UPI_CPU0_CPU1_P0P1_DN<8>")
		)
		(pad "AF4" smd circle
			(at -34.98342 -15.326868 270)
			(size 0.4318 0.4318)
			(layers "F.Cu" "F.Mask" "F.Paste")
			(net "GND")
		)
		(pad "AF6" smd circle
			(at -33.355534 -15.326868 270)
			(size 0.4318 0.4318)
			(layers "F.Cu" "F.Mask" "F.Paste")
			(net "UPI_CPU1_CPU0_P1P0_DN<8>")
		)
		(pad "AF8" smd circle
			(at -31.727902 -15.326868 270)
			(size 0.4318 0.4318)
			(layers "F.Cu" "F.Mask" "F.Paste")
			(net "GND")
		)
		(pad "AF10" smd circle
			(at -30.100016 -15.326868 270)
			(size 0.4318 0.4318)
			(layers "F.Cu" "F.Mask" "F.Paste")
			(net "P5E_CPU0_PE0_RX_DN<8>")
		)
		(pad "AF12" smd circle
			(at -28.472384 -15.326868 270)
			(size 0.4318 0.4318)
			(layers "F.Cu" "F.Mask" "F.Paste")
			(net "GND")
		)
		(pad "AF14" smd circle
			(at -26.844498 -15.326868 270)
			(size 0.4318 0.4318)
			(layers "F.Cu" "F.Mask" "F.Paste")
			(net "P5E_CPU0_PE0_TX_DN<7>")
		)
		(pad "AF16" smd circle
			(at -25.216612 -15.326868 270)
			(size 0.4318 0.4318)
			(layers "F.Cu" "F.Mask" "F.Paste")
			(net "GND")
		)
		(pad "AF18" smd circle
			(at -23.58898 -15.326868 270)
			(size 0.4318 0.4318)
			(layers "F.Cu" "F.Mask" "F.Paste")
			(net "M_C_CPU0_SB_DQS_DN<8>")
		)
		(pad "AF20" smd circle
			(at -21.961094 -15.326868 270)
			(size 0.4318 0.4318)
			(layers "F.Cu" "F.Mask" "F.Paste")
			(net "M_C_CPU0_SB_DQ<26>")
		)
		(pad "AF22" smd circle
			(at -20.333462 -15.326868 270)
			(size 0.4318 0.4318)
			(layers "F.Cu" "F.Mask" "F.Paste")
			(net "M_D_CPU0_SB_DQ<23>")
		)
		(pad "AF24" smd circle
			(at -18.705576 -15.326868 270)
			(size 0.4318 0.4318)
			(layers "F.Cu" "F.Mask" "F.Paste")
			(net "M_D_CPU0_SB_DQS_DN<7>")
		)
		(pad "AF26" smd circle
			(at -17.07769 -15.326868 270)
			(size 0.4318 0.4318)
			(layers "F.Cu" "F.Mask" "F.Paste")
			(net "M_D_CPU0_SB_DQ<18>")
		)
		(pad "AF28" smd circle
			(at -15.450058 -15.326868 270)
			(size 0.4318 0.4318)
			(layers "F.Cu" "F.Mask" "F.Paste")
			(net "M_C_CPU0_SB_DQ<15>")
		)
		(pad "AF30" smd circle
			(at -13.822426 -15.326868 270)
			(size 0.4318 0.4318)
			(layers "F.Cu" "F.Mask" "F.Paste")
			(net "M_C_CPU0_SB_DQS_DN<6>")
		)
		(pad "AF32" smd circle
			(at -12.19454 -15.326868 270)
			(size 0.4318 0.4318)
			(layers "F.Cu" "F.Mask" "F.Paste")
			(net "M_C_CPU0_SB_DQ<10>")
		)
		(pad "AF34" smd circle
			(at -10.566654 -15.326868 270)
			(size 0.4318 0.4318)
			(layers "F.Cu" "F.Mask" "F.Paste")
			(net "M_C_CPU0_SB_DQ<7>")
		)
		(pad "AF36" smd circle
			(at -8.939022 -15.326868 270)
			(size 0.4318 0.4318)
			(layers "F.Cu" "F.Mask" "F.Paste")
			(net "M_C_CPU0_SB_DQS_DN<5>")
		)
		(pad "AF38" smd circle
			(at -7.311136 -15.326868 270)
			(size 0.4318 0.4318)
			(layers "F.Cu" "F.Mask" "F.Paste")
			(net "M_C_CPU0_SB_DQ<2>")
		)
		(pad "AF40" smd circle
			(at -5.68325 -15.326868 270)
			(size 0.4318 0.4318)
			(layers "F.Cu" "F.Mask" "F.Paste")
			(net "M_D_CPU0_SB_CS_N<2>")
		)
		(pad "AF42" smd circle
			(at -4.055618 -15.326868 270)
			(size 0.4318 0.4318)
			(layers "F.Cu" "F.Mask" "F.Paste")
			(net "GND")
		)
		(pad "AF44" smd circle
			(at -2.427732 -15.326868 270)
			(size 0.4318 0.4318)
			(layers "F.Cu" "F.Mask" "F.Paste")
			(net "M_D_CPU0_SB_CA<3>")
		)
		(pad "AF47" smd circle
			(at 1.613916 -15.216886 270)
			(size 0.4318 0.4318)
			(layers "F.Cu" "F.Mask" "F.Paste")
			(net "M_C_CPU0_SB_RSP<1>")
		)
		(pad "AF49" smd circle
			(at 3.241802 -15.216886 270)
			(size 0.4318 0.4318)
			(layers "F.Cu" "F.Mask" "F.Paste")
			(net "M_C_CPU0_CLK_DN<1>")
		)
		(pad "AF51" smd circle
			(at 4.869434 -15.216886 270)
			(size 0.4318 0.4318)
			(layers "F.Cu" "F.Mask" "F.Paste")
			(net "M_D_CPU0_SB_RSP<0>")
		)
		(pad "AF53" smd circle
			(at 6.49732 -15.216886 270)
			(size 0.4318 0.4318)
			(layers "F.Cu" "F.Mask" "F.Paste")
			(net "M_C_CPU0_SA_CB<7>")
		)
		(pad "AF55" smd circle
			(at 8.124952 -15.216886 270)
			(size 0.4318 0.4318)
			(layers "F.Cu" "F.Mask" "F.Paste")
			(net "M_C_CPU0_SA_DQS_DP<9>")
		)
		(pad "AF57" smd circle
			(at 9.752838 -15.216886 270)
			(size 0.4318 0.4318)
			(layers "F.Cu" "F.Mask" "F.Paste")
			(net "M_C_CPU0_SA_CB<2>")
		)
		(pad "AF59" smd circle
			(at 11.380724 -15.216886 270)
			(size 0.4318 0.4318)
			(layers "F.Cu" "F.Mask" "F.Paste")
			(net "M_C_CPU0_SA_DQ<31>")
		)
		(pad "AF61" smd circle
			(at 13.008356 -15.216886 270)
			(size 0.4318 0.4318)
			(layers "F.Cu" "F.Mask" "F.Paste")
			(net "M_C_CPU0_SA_DQS_DN<8>")
		)
		(pad "AF63" smd circle
			(at 14.635988 -15.216886 270)
			(size 0.4318 0.4318)
			(layers "F.Cu" "F.Mask" "F.Paste")
			(net "M_C_CPU0_SA_DQ<26>")
		)
		(pad "AF65" smd circle
			(at 16.263874 -15.216886 270)
			(size 0.4318 0.4318)
			(layers "F.Cu" "F.Mask" "F.Paste")
			(net "M_C_CPU0_SA_DQ<15>")
		)
		(pad "AF67" smd circle
			(at 17.89176 -15.216886 270)
			(size 0.4318 0.4318)
			(layers "F.Cu" "F.Mask" "F.Paste")
			(net "M_C_CPU0_SA_DQS_DP<6>")
		)
		(pad "AF69" smd circle
			(at 19.519392 -15.216886 270)
			(size 0.4318 0.4318)
			(layers "F.Cu" "F.Mask" "F.Paste")
			(net "M_C_CPU0_SA_DQ<10>")
		)
		(pad "AF71" smd circle
			(at 21.147278 -15.216886 270)
			(size 0.4318 0.4318)
			(layers "F.Cu" "F.Mask" "F.Paste")
			(net "M_D_CPU0_SA_DQ<7>")
		)
		(pad "AF73" smd circle
			(at 22.77491 -15.216886 270)
			(size 0.4318 0.4318)
			(layers "F.Cu" "F.Mask" "F.Paste")
			(net "M_D_CPU0_SA_DQS_DP<5>")
		)
		(pad "AF75" smd circle
			(at 24.402796 -15.216886 270)
			(size 0.4318 0.4318)
			(layers "F.Cu" "F.Mask" "F.Paste")
			(net "M_D_CPU0_SA_DQ<2>")
		)
		(pad "AF77" smd circle
			(at 26.030682 -15.216886 270)
			(size 0.4318 0.4318)
			(layers "F.Cu" "F.Mask" "F.Paste")
			(net "PVCCFA_EHV_FIVRA_CPU0")
		)
		(pad "AF79" smd circle
			(at 27.658314 -15.216886 270)
			(size 0.4318 0.4318)
			(layers "F.Cu" "F.Mask" "F.Paste")
			(net "UPI_CPU1_CPU0_P2P2_DP<15>")
		)
		(pad "AF81" smd circle
			(at 29.2862 -15.216886 270)
			(size 0.4318 0.4318)
			(layers "F.Cu" "F.Mask" "F.Paste")
			(net "GND")
		)
		(pad "AF83" smd circle
			(at 30.914086 -15.216886 270)
			(size 0.4318 0.4318)
			(layers "F.Cu" "F.Mask" "F.Paste")
			(net "UPI_CPU1_CPU0_P2P2_DN<14>")
		)
		(pad "AF85" smd circle
			(at 32.541718 -15.216886 270)
			(size 0.4318 0.4318)
			(layers "F.Cu" "F.Mask" "F.Paste")
			(net "P5E_CPU0_PE4_TX_DP<7>")
		)
		(pad "AF87" smd circle
			(at 34.169604 -15.216886 270)
			(size 0.4318 0.4318)
			(layers "F.Cu" "F.Mask" "F.Paste")
			(net "GND")
		)
		(pad "AF89" smd circle
			(at 35.797236 -15.216886 270)
			(size 0.4318 0.4318)
			(layers "F.Cu" "F.Mask" "F.Paste")
			(net "P5E_CPU0_PE4_RX_DN<7>")
		)
		(pad "AF91" smd oval
			(at 37.425122 -15.216886)
			(size 0.381 0.4826)
			(drill
				(offset 0 -0.0508)
			)
			(layers "F.Cu" "F.Mask" "F.Paste")
			(net "GND")
		)
		(pad "AG1" smd oval
			(at -37.425122 -14.856714 180)
			(size 0.381 0.4826)
			(drill
				(offset 0 -0.0508)
			)
			(layers "F.Cu" "F.Mask" "F.Paste")
			(net "GND")
		)
		(pad "AG3" smd circle
			(at -35.797236 -14.856714 270)
			(size 0.4318 0.4318)
			(layers "F.Cu" "F.Mask" "F.Paste")
			(net "UPI_CPU0_CPU1_P0P1_DP<9>")
		)
		(pad "AG5" smd circle
			(at -34.169604 -14.856714 270)
			(size 0.4318 0.4318)
			(layers "F.Cu" "F.Mask" "F.Paste")
			(net "GND")
		)
		(pad "AG7" smd circle
			(at -32.541718 -14.856714 270)
			(size 0.4318 0.4318)
			(layers "F.Cu" "F.Mask" "F.Paste")
			(net "UPI_CPU1_CPU0_P1P0_DP<8>")
		)
		(pad "AG9" smd circle
			(at -30.914086 -14.856714 270)
			(size 0.4318 0.4318)
			(layers "F.Cu" "F.Mask" "F.Paste")
			(net "GND")
		)
		(pad "AG11" smd circle
			(at -29.2862 -14.856714 270)
			(size 0.4318 0.4318)
			(layers "F.Cu" "F.Mask" "F.Paste")
			(net "P5E_CPU0_PE0_RX_DP<8>")
		)
		(pad "AG13" smd circle
			(at -27.658314 -14.856714 270)
			(size 0.4318 0.4318)
			(layers "F.Cu" "F.Mask" "F.Paste")
			(net "GND")
		)
		(pad "AG15" smd circle
			(at -26.030682 -14.856714 270)
			(size 0.4318 0.4318)
			(layers "F.Cu" "F.Mask" "F.Paste")
			(net "P5E_CPU0_PE0_TX_DP<7>")
		)
		(pad "AG17" smd circle
			(at -24.402796 -14.856714 270)
			(size 0.4318 0.4318)
			(layers "F.Cu" "F.Mask" "F.Paste")
			(net "M_C_CPU0_SB_DQ<29>")
		)
		(pad "AG19" smd circle
			(at -22.77491 -14.856714 270)
			(size 0.4318 0.4318)
			(layers "F.Cu" "F.Mask" "F.Paste")
			(net "M_C_CPU0_SB_DQ<27>")
		)
		(pad "AG21" smd circle
			(at -21.147278 -14.856714 270)
			(size 0.4318 0.4318)
			(layers "F.Cu" "F.Mask" "F.Paste")
			(net "GND")
		)
		(pad "AG23" smd circle
			(at -19.519392 -14.856714 270)
			(size 0.4318 0.4318)
			(layers "F.Cu" "F.Mask" "F.Paste")
			(net "M_D_CPU0_SB_DQ<22>")
		)
		(pad "AG25" smd circle
			(at -17.89176 -14.856714 270)
			(size 0.4318 0.4318)
			(layers "F.Cu" "F.Mask" "F.Paste")
			(net "M_D_CPU0_SB_DQ<19>")
		)
		(pad "AG27" smd circle
			(at -16.263874 -14.856714 270)
			(size 0.4318 0.4318)
			(layers "F.Cu" "F.Mask" "F.Paste")
			(net "GND")
		)
		(pad "AG29" smd circle
			(at -14.635988 -14.856714 270)
			(size 0.4318 0.4318)
			(layers "F.Cu" "F.Mask" "F.Paste")
			(net "M_C_CPU0_SB_DQ<14>")
		)
		(pad "AG31" smd circle
			(at -13.008356 -14.856714 270)
			(size 0.4318 0.4318)
			(layers "F.Cu" "F.Mask" "F.Paste")
			(net "M_C_CPU0_SB_DQ<11>")
		)
		(pad "AG33" smd circle
			(at -11.380724 -14.856714 270)
			(size 0.4318 0.4318)
			(layers "F.Cu" "F.Mask" "F.Paste")
			(net "GND")
		)
		(pad "AG35" smd circle
			(at -9.752838 -14.856714 270)
			(size 0.4318 0.4318)
			(layers "F.Cu" "F.Mask" "F.Paste")
			(net "M_C_CPU0_SB_DQ<6>")
		)
		(pad "AG37" smd circle
			(at -8.124952 -14.856714 270)
			(size 0.4318 0.4318)
			(layers "F.Cu" "F.Mask" "F.Paste")
			(net "M_C_CPU0_SB_DQ<3>")
		)
		(pad "AG39" smd circle
			(at -6.49732 -14.856714 270)
			(size 0.4318 0.4318)
			(layers "F.Cu" "F.Mask" "F.Paste")
			(net "GND")
		)
		(pad "AG41" smd circle
			(at -4.869434 -14.856714 270)
			(size 0.4318 0.4318)
			(layers "F.Cu" "F.Mask" "F.Paste")
			(net "M_D_CPU0_SB_CS_N<1>")
		)
		(pad "AG43" smd circle
			(at -3.241802 -14.856714 270)
			(size 0.4318 0.4318)
			(layers "F.Cu" "F.Mask" "F.Paste")
			(net "M_D_CPU0_SB_CA<5>")
		)
	)
)
